# T6G (Grand Teton) — schematic netlist excerpt (pin names and nets, part order shuffled) for the footprints in the layout excerpt that follows; sources: Cadence DE-HDL packaged netlist, KiCad conversion of 04192023_DAF0TMB3IC0_F0TG_MB_C_brd_V02_OCP.brd

C1512  Q_CAP  33PF 50V 5% NPO  pkg 0402  page 172 : A = JTAG_DBREQ_N ; B = GND
C105  Q_CAP  0.1UF 25V 10% EMPTY  pkg 0402  page 361 : A = P1V8_RETIMER_CPU1_EN ; B = GND

(kicad_pcb
	(version 20260206)
	(generator "pcbnew")
	(generator_version "10.0")
	(general
		(thickness 1.6)
		(legacy_teardrops no)
	)
	(paper "A4")
	(title_block
		(title "04192023_DAF0TMB3IC0_F0TG_MB_C_brd_V02_OCP.brd")
		(comment 1 "Grand Teton / footprints 4457-4458 of 8354")
	)
	(layers
		(0 "F.Cu" signal "TOP")
		(4 "In1.Cu" signal "GND")
		(6 "In2.Cu" signal "IN1")
		(8 "In3.Cu" signal "GND1")
		(10 "In4.Cu" signal "IN2")
		(12 "In5.Cu" signal "GND2")
		(14 "In6.Cu" signal "IN3")
		(16 "In7.Cu" signal "GND3")
		(18 "In8.Cu" signal "VCC")
		(20 "In9.Cu" signal "VCC1")
		(22 "In10.Cu" signal "GND4")
		(24 "In11.Cu" signal "IN4")
		(26 "In12.Cu" signal "GND5")
		(28 "In13.Cu" signal "IN5")
		(30 "In14.Cu" signal "GND6")
		(32 "In15.Cu" signal "IN6")
		(34 "In16.Cu" signal "GND7")
		(2 "B.Cu" signal "BOTTOM")
		(9 "F.Adhes" user "F.Adhesive")
		(11 "B.Adhes" user "B.Adhesive")
		(13 "F.Paste" user "Package Geometry/Pastemask Top")
		(15 "B.Paste" user "Package Geometry/Pastemask Bottom")
		(5 "F.SilkS" user "Ref Des/Silkscreen Top")
		(7 "B.SilkS" user "Ref Des/Silkscreen Bottom")
		(1 "F.Mask" user "Board Geometry/Soldermask Top")
		(3 "B.Mask" user "Board Geometry/Soldermask Bottom")
		(17 "Dwgs.User" user "User.Drawings")
		(19 "Cmts.User" user "User.Comments")
		(21 "Eco1.User" user "User.Eco1")
		(23 "Eco2.User" user "User.Eco2")
		(25 "Edge.Cuts" user "Board Geometry/Outline")
		(27 "Margin" user)
		(31 "F.CrtYd" user "Package Geometry/Place Bound Top")
		(29 "B.CrtYd" user "Package Geometry/Place Bound Bottom")
		(35 "F.Fab" user "Ref Des/Assembly Top")
		(33 "B.Fab" user "Ref Des/Assembly Bottom")
	)
	(footprint ""
		(layer "F.Cu")
		(at 227.488242 -289.012122 180)
		(property "Reference" "C105"
			(at 0 0 180)
			(layer "F.SilkS")
			(hide yes)
			(effects
				(font
					(size 1.27 1.27)
				)
			)
		)
		(property "Value" ""
			(at 0 0 180)
			(layer "F.Fab")
			(effects
				(font
					(size 1.27 1.27)
				)
			)
		)
		(duplicate_pad_numbers_are_jumpers no)
		(fp_line
			(start 0.7874 0.4064)
			(end -0.7874 0.4064)
			(stroke
				(width 0.1524)
				(type default)
			)
			(layer "F.SilkS")
		)
		(fp_line
			(start 0.7874 -0.4064)
			(end 0.7874 0.4064)
			(stroke
				(width 0.1524)
				(type default)
			)
			(layer "F.SilkS")
		)
		(fp_line
			(start -0.7874 0.4064)
			(end -0.7874 -0.4064)
			(stroke
				(width 0.1524)
				(type default)
			)
			(layer "F.SilkS")
		)
		(fp_line
			(start -0.7874 -0.4064)
			(end 0.7874 -0.4064)
			(stroke
				(width 0.1524)
				(type default)
			)
			(layer "F.SilkS")
		)
		(fp_line
			(start 0.67945 0.3048)
			(end 0.120396 0.3048)
			(stroke
				(width 0.1)
				(type default)
			)
			(layer "F.Fab")
		)
		(fp_line
			(start 0.67945 -0.3048)
			(end 0.67945 0.3048)
			(stroke
				(width 0.1)
				(type default)
			)
			(layer "F.Fab")
		)
		(fp_line
			(start 0.12065 -0.2794)
			(end 0.12065 -0.3048)
			(stroke
				(width 0.1)
				(type default)
			)
			(layer "F.Fab")
		)
		(fp_line
			(start 0.12065 -0.3048)
			(end 0.67945 -0.3048)
			(stroke
				(width 0.1)
				(type default)
			)
			(layer "F.Fab")
		)
		(fp_line
			(start 0.120396 0.3048)
			(end 0.120396 0.2794)
			(stroke
				(width 0.1)
				(type default)
			)
			(layer "F.Fab")
		)
		(fp_line
			(start 0.120396 0.2794)
			(end -0.12065 0.2794)
			(stroke
				(width 0.1)
				(type default)
			)
			(layer "F.Fab")
		)
		(fp_line
			(start -0.12065 0.3048)
			(end -0.67945 0.3048)
			(stroke
				(width 0.1)
				(type default)
			)
			(layer "F.Fab")
		)
		(fp_line
			(start -0.12065 0.2794)
			(end -0.12065 0.3048)
			(stroke
				(width 0.1)
				(type default)
			)
			(layer "F.Fab")
		)
		(fp_line
			(start -0.12065 -0.2794)
			(end 0.12065 -0.2794)
			(stroke
				(width 0.1)
				(type default)
			)
			(layer "F.Fab")
		)
		(fp_line
			(start -0.12065 -0.305054)
			(end -0.12065 -0.2794)
			(stroke
				(width 0.1)
				(type default)
			)
			(layer "F.Fab")
		)
		(fp_line
			(start -0.67945 0.3048)
			(end -0.67945 -0.305054)
			(stroke
				(width 0.1)
				(type default)
			)
			(layer "F.Fab")
		)
		(fp_line
			(start -0.67945 -0.305054)
			(end -0.12065 -0.305054)
			(stroke
				(width 0.1)
				(type default)
			)
			(layer "F.Fab")
		)
		(pad "1" smd circle
			(at -0.40005 0 180)
			(size 0 0)
			(layers "F.Cu" "F.Mask" "F.Paste")
			(net "P1V8_RETIMER_CPU1_EN")
		)
		(pad "2" smd circle
			(at 0.40005 0 180)
			(size 0 0)
			(layers "F.Cu" "F.Mask" "F.Paste")
			(net "GND")
		)
	)
	(footprint ""
		(layer "F.Cu")
		(at 259.831586 -101.022404)
		(property "Reference" "C1512"
			(at 0 0 0)
			(layer "F.SilkS")
			(hide yes)
			(effects
				(font
					(size 1.27 1.27)
				)
			)
		)
		(property "Value" ""
			(at 0 0 0)
			(layer "F.Fab")
			(effects
				(font
					(size 1.27 1.27)
				)
			)
		)
		(duplicate_pad_numbers_are_jumpers no)
		(fp_line
			(start -0.7874 -0.4064)
			(end 0.7874 -0.4064)
			(stroke
				(width 0.1524)
				(type default)
			)
			(layer "F.SilkS")
		)
		(fp_line
			(start -0.7874 0.4064)
			(end -0.7874 -0.4064)
			(stroke
				(width 0.1524)
				(type default)
			)
			(layer "F.SilkS")
		)
		(fp_line
			(start 0.7874 -0.4064)
			(end 0.7874 0.4064)
			(stroke
				(width 0.1524)
				(type default)
			)
			(layer "F.SilkS")
		)
		(fp_line
			(start 0.7874 0.4064)
			(end -0.7874 0.4064)
			(stroke
				(width 0.1524)
				(type default)
			)
			(layer "F.SilkS")
		)
		(fp_line
			(start -0.67945 -0.305054)
			(end -0.12065 -0.305054)
			(stroke
				(width 0.1)
				(type default)
			)
			(layer "F.Fab")
		)
		(fp_line
			(start -0.67945 0.3048)
			(end -0.67945 -0.305054)
			(stroke
				(width 0.1)
				(type default)
			)
			(layer "F.Fab")
		)
		(fp_line
			(start -0.12065 -0.305054)
			(end -0.12065 -0.2794)
			(stroke
				(width 0.1)
				(type default)
			)
			(layer "F.Fab")
		)
		(fp_line
			(start -0.12065 -0.2794)
			(end 0.12065 -0.2794)
			(stroke
				(width 0.1)
				(type default)
			)
			(layer "F.Fab")
		)
		(fp_line
			(start -0.12065 0.2794)
			(end -0.12065 0.3048)
			(stroke
				(width 0.1)
				(type default)
			)
			(layer "F.Fab")
		)
		(fp_line
			(start -0.12065 0.3048)
			(end -0.67945 0.3048)
			(stroke
				(width 0.1)
				(type default)
			)
			(layer "F.Fab")
		)
		(fp_line
			(start 0.120396 0.2794)
			(end -0.12065 0.2794)
			(stroke
				(width 0.1)
				(type default)
			)
			(layer "F.Fab")
		)
		(fp_line
			(start 0.120396 0.3048)
			(end 0.120396 0.2794)
			(stroke
				(width 0.1)
				(type default)
			)
			(layer "F.Fab")
		)
		(fp_line
			(start 0.12065 -0.3048)
			(end 0.67945 -0.3048)
			(stroke
				(width 0.1)
				(type default)
			)
			(layer "F.Fab")
		)
		(fp_line
			(start 0.12065 -0.2794)
			(end 0.12065 -0.3048)
			(stroke
				(width 0.1)
				(type default)
			)
			(layer "F.Fab")
		)
		(fp_line
			(start 0.67945 -0.3048)
			(end 0.67945 0.3048)
			(stroke
				(width 0.1)
				(type default)
			)
			(layer "F.Fab")
		)
		(fp_line
			(start 0.67945 0.3048)
			(end 0.120396 0.3048)
			(stroke
				(width 0.1)
				(type default)
			)
			(layer "F.Fab")
		)
		(pad "1" smd circle
			(at -0.40005 0)
			(size 0 0)
			(layers "F.Cu" "F.Mask" "F.Paste")
			(net "JTAG_DBREQ_N")
		)
		(pad "2" smd circle
			(at 0.40005 0)
			(size 0 0)
			(layers "F.Cu" "F.Mask" "F.Paste")
			(net "GND")
		)
	)
)
